# S9S_MB_2U (Grand Teton) — schematic netlist excerpt (pin names and nets, part order shuffled) for the footprints in the layout excerpt that follows; sources: Cadence DE-HDL packaged netlist, KiCad conversion of 03242023_DA0F0TMBIJ0_F0T_Motherboard_J_brd_V01_OCP.brd

C490  Q_CAP  22UF 4V 20% X6S  pkg C0402  page 78 : A = PVCCINFAON_CPU1 ; B = GND
PR152  Q_RES  2.2 1% CHIP  pkg 0402LF  page 267 : A = PVCCIN_CPU0_PVCC ; B = PVCCIN_CPU0_VDD2

(kicad_pcb
	(version 20260206)
	(generator "pcbnew")
	(generator_version "10.0")
	(general
		(thickness 1.6)
		(legacy_teardrops no)
	)
	(paper "A4")
	(title_block
		(title "03242023_DA0F0TMBIJ0_F0T_Motherboard_J_brd_V01_OCP.brd")
		(comment 1 "Grand Teton / footprints 5107-5108 of 6105")
	)
	(layers
		(0 "F.Cu" signal "TOP")
		(4 "In1.Cu" signal "GND")
		(6 "In2.Cu" signal "IN1")
		(8 "In3.Cu" signal "GND1")
		(10 "In4.Cu" signal "IN2")
		(12 "In5.Cu" signal "GND2")
		(14 "In6.Cu" signal "IN3")
		(16 "In7.Cu" signal "GND3")
		(18 "In8.Cu" signal "VCC")
		(20 "In9.Cu" signal "VCC1")
		(22 "In10.Cu" signal "GND4")
		(24 "In11.Cu" signal "IN4")
		(26 "In12.Cu" signal "GND5")
		(28 "In13.Cu" signal "IN5")
		(30 "In14.Cu" signal "GND6")
		(32 "In15.Cu" signal "IN6")
		(34 "In16.Cu" signal "GND7")
		(2 "B.Cu" signal "BOTTOM")
		(9 "F.Adhes" user "F.Adhesive")
		(11 "B.Adhes" user "B.Adhesive")
		(13 "F.Paste" user "Package Geometry/Pastemask Top")
		(15 "B.Paste" user "Package Geometry/Pastemask Bottom")
		(5 "F.SilkS" user "Ref Des/Silkscreen Top")
		(7 "B.SilkS" user "Ref Des/Silkscreen Bottom")
		(1 "F.Mask" user "Board Geometry/Soldermask Top")
		(3 "B.Mask" user "Board Geometry/Soldermask Bottom")
		(17 "Dwgs.User" user "User.Drawings")
		(19 "Cmts.User" user "User.Comments")
		(21 "Eco1.User" user "User.Eco1")
		(23 "Eco2.User" user "User.Eco2")
		(25 "Edge.Cuts" user "Board Geometry/Outline")
		(27 "Margin" user)
		(31 "F.CrtYd" user "Package Geometry/Place Bound Top")
		(29 "B.CrtYd" user "Package Geometry/Place Bound Bottom")
		(35 "F.Fab" user "Ref Des/Assembly Top")
		(33 "B.Fab" user "Ref Des/Assembly Bottom")
	)
	(footprint ""
		(layer "B.Cu")
		(at 350.849438 -334.845152 -90)
		(property "Reference" "PR152"
			(at 0 0 90)
			(layer "B.SilkS")
			(hide yes)
			(effects
				(font
					(size 1.27 1.27)
				)
				(justify mirror)
			)
		)
		(property "Value" ""
			(at 0 0 90)
			(layer "B.Fab")
			(effects
				(font
					(size 1.27 1.27)
				)
				(justify mirror)
			)
		)
		(duplicate_pad_numbers_are_jumpers no)
		(fp_line
			(start -0.7874 0.4064)
			(end 0.7874 0.4064)
			(stroke
				(width 0.1524)
				(type default)
			)
			(layer "B.SilkS")
		)
		(fp_line
			(start 0.7874 0.4064)
			(end 0.7874 -0.4064)
			(stroke
				(width 0.1524)
				(type default)
			)
			(layer "B.SilkS")
		)
		(fp_line
			(start -0.7874 -0.4064)
			(end -0.7874 0.4064)
			(stroke
				(width 0.1524)
				(type default)
			)
			(layer "B.SilkS")
		)
		(fp_line
			(start 0.7874 -0.4064)
			(end -0.7874 -0.4064)
			(stroke
				(width 0.1524)
				(type default)
			)
			(layer "B.SilkS")
		)
		(fp_line
			(start -0.67945 0.3048)
			(end -0.120396 0.3048)
			(stroke
				(width 0.1)
				(type default)
			)
			(layer "B.Fab")
		)
		(fp_line
			(start -0.120396 0.3048)
			(end -0.120396 0.2794)
			(stroke
				(width 0.1)
				(type default)
			)
			(layer "B.Fab")
		)
		(fp_line
			(start 0.12065 0.3048)
			(end 0.67945 0.3048)
			(stroke
				(width 0.1)
				(type default)
			)
			(layer "B.Fab")
		)
		(fp_line
			(start 0.67945 0.3048)
			(end 0.67945 -0.305054)
			(stroke
				(width 0.1)
				(type default)
			)
			(layer "B.Fab")
		)
		(fp_line
			(start -0.120396 0.2794)
			(end 0.12065 0.2794)
			(stroke
				(width 0.1)
				(type default)
			)
			(layer "B.Fab")
		)
		(fp_line
			(start 0.12065 0.2794)
			(end 0.12065 0.3048)
			(stroke
				(width 0.1)
				(type default)
			)
			(layer "B.Fab")
		)
		(fp_line
			(start -0.12065 -0.2794)
			(end -0.12065 -0.3048)
			(stroke
				(width 0.1)
				(type default)
			)
			(layer "B.Fab")
		)
		(fp_line
			(start 0.12065 -0.2794)
			(end -0.12065 -0.2794)
			(stroke
				(width 0.1)
				(type default)
			)
			(layer "B.Fab")
		)
		(fp_line
			(start -0.67945 -0.3048)
			(end -0.67945 0.3048)
			(stroke
				(width 0.1)
				(type default)
			)
			(layer "B.Fab")
		)
		(fp_line
			(start -0.12065 -0.3048)
			(end -0.67945 -0.3048)
			(stroke
				(width 0.1)
				(type default)
			)
			(layer "B.Fab")
		)
		(fp_line
			(start 0.12065 -0.305054)
			(end 0.12065 -0.2794)
			(stroke
				(width 0.1)
				(type default)
			)
			(layer "B.Fab")
		)
		(fp_line
			(start 0.67945 -0.305054)
			(end 0.12065 -0.305054)
			(stroke
				(width 0.1)
				(type default)
			)
			(layer "B.Fab")
		)
		(pad "1" smd circle
			(at 0.40005 0 90)
			(size 0 0)
			(layers "B.Cu" "B.Mask" "B.Paste")
			(net "PVCCIN_CPU0_PVCC")
		)
		(pad "2" smd circle
			(at -0.40005 0 90)
			(size 0 0)
			(layers "B.Cu" "B.Mask" "B.Paste")
			(net "PVCCIN_CPU0_VDD2")
		)
	)
	(footprint ""
		(layer "B.Cu")
		(at 120.145302 -262.032496 -90)
		(property "Reference" "C490"
			(at 0 0 90)
			(layer "B.SilkS")
			(hide yes)
			(effects
				(font
					(size 1.27 1.27)
				)
				(justify mirror)
			)
		)
		(property "Value" ""
			(at 0 0 90)
			(layer "B.Fab")
			(effects
				(font
					(size 1.27 1.27)
				)
				(justify mirror)
			)
		)
		(duplicate_pad_numbers_are_jumpers no)
		(fp_line
			(start -0.7874 0.4064)
			(end 0.7874 0.4064)
			(stroke
				(width 0.1524)
				(type default)
			)
			(layer "B.SilkS")
		)
		(fp_line
			(start 0.7874 0.4064)
			(end 0.7874 -0.4064)
			(stroke
				(width 0.1524)
				(type default)
			)
			(layer "B.SilkS")
		)
		(fp_line
			(start -0.7874 -0.4064)
			(end -0.7874 0.4064)
			(stroke
				(width 0.1524)
				(type default)
			)
			(layer "B.SilkS")
		)
		(fp_line
			(start 0.7874 -0.4064)
			(end -0.7874 -0.4064)
			(stroke
				(width 0.1524)
				(type default)
			)
			(layer "B.SilkS")
		)
		(fp_line
			(start -0.67945 0.3048)
			(end -0.120396 0.3048)
			(stroke
				(width 0.1)
				(type default)
			)
			(layer "B.Fab")
		)
		(fp_line
			(start -0.120396 0.3048)
			(end -0.120396 0.2794)
			(stroke
				(width 0.1)
				(type default)
			)
			(layer "B.Fab")
		)
		(fp_line
			(start 0.12065 0.3048)
			(end 0.67945 0.3048)
			(stroke
				(width 0.1)
				(type default)
			)
			(layer "B.Fab")
		)
		(fp_line
			(start 0.67945 0.3048)
			(end 0.67945 -0.305054)
			(stroke
				(width 0.1)
				(type default)
			)
			(layer "B.Fab")
		)
		(fp_line
			(start -0.120396 0.2794)
			(end 0.12065 0.2794)
			(stroke
				(width 0.1)
				(type default)
			)
			(layer "B.Fab")
		)
		(fp_line
			(start 0.12065 0.2794)
			(end 0.12065 0.3048)
			(stroke
				(width 0.1)
				(type default)
			)
			(layer "B.Fab")
		)
		(fp_line
			(start -0.12065 -0.2794)
			(end -0.12065 -0.3048)
			(stroke
				(width 0.1)
				(type default)
			)
			(layer "B.Fab")
		)
		(fp_line
			(start 0.12065 -0.2794)
			(end -0.12065 -0.2794)
			(stroke
				(width 0.1)
				(type default)
			)
			(layer "B.Fab")
		)
		(fp_line
			(start -0.67945 -0.3048)
			(end -0.67945 0.3048)
			(stroke
				(width 0.1)
				(type default)
			)
			(layer "B.Fab")
		)
		(fp_line
			(start -0.12065 -0.3048)
			(end -0.67945 -0.3048)
			(stroke
				(width 0.1)
				(type default)
			)
			(layer "B.Fab")
		)
		(fp_line
			(start 0.12065 -0.305054)
			(end 0.12065 -0.2794)
			(stroke
				(width 0.1)
				(type default)
			)
			(layer "B.Fab")
		)
		(fp_line
			(start 0.67945 -0.305054)
			(end 0.12065 -0.305054)
			(stroke
				(width 0.1)
				(type default)
			)
			(layer "B.Fab")
		)
		(pad "1" smd circle
			(at 0.40005 0 90)
			(size 0 0)
			(layers "B.Cu" "B.Mask" "B.Paste")
			(net "PVCCINFAON_CPU1")
		)
		(pad "2" smd circle
			(at -0.40005 0 90)
			(size 0 0)
			(layers "B.Cu" "B.Mask" "B.Paste")
			(net "GND")
		)
	)
)
